(kicad_pcb
	(version 20260206)
	(generator "pcbnew")
	(generator_version "10.0")
	(general
		(thickness 1.6)
		(legacy_teardrops no)
	)
	(paper "A4")
	(title_block
		(title "04192023_DAF0TMB3IC0_F0TG_MB_C_brd_V02_OCP.brd")
		(comment 1 "Grand Teton / footprints 2349-2349 of 8354")
	)
	(layers
		(0 "F.Cu" signal "TOP")
		(4 "In1.Cu" signal "GND")
		(6 "In2.Cu" signal "IN1")
		(8 "In3.Cu" signal "GND1")
		(10 "In4.Cu" signal "IN2")
		(12 "In5.Cu" signal "GND2")
		(14 "In6.Cu" signal "IN3")
		(16 "In7.Cu" signal "GND3")
		(18 "In8.Cu" signal "VCC")
		(20 "In9.Cu" signal "VCC1")
		(22 "In10.Cu" signal "GND4")
		(24 "In11.Cu" signal "IN4")
		(26 "In12.Cu" signal "GND5")
		(28 "In13.Cu" signal "IN5")
		(30 "In14.Cu" signal "GND6")
		(32 "In15.Cu" signal "IN6")
		(34 "In16.Cu" signal "GND7")
		(2 "B.Cu" signal "BOTTOM")
		(9 "F.Adhes" user "F.Adhesive")
		(11 "B.Adhes" user "B.Adhesive")
		(13 "F.Paste" user "Package Geometry/Pastemask Top")
		(15 "B.Paste" user "Package Geometry/Pastemask Bottom")
		(5 "F.SilkS" user "Ref Des/Silkscreen Top")
		(7 "B.SilkS" user "Ref Des/Silkscreen Bottom")
		(1 "F.Mask" user "Board Geometry/Soldermask Top")
		(3 "B.Mask" user "Board Geometry/Soldermask Bottom")
		(17 "Dwgs.User" user "User.Drawings")
		(19 "Cmts.User" user "User.Comments")
		(21 "Eco1.User" user "User.Eco1")
		(23 "Eco2.User" user "User.Eco2")
		(25 "Edge.Cuts" user "Board Geometry/Outline")
		(27 "Margin" user)
		(31 "F.CrtYd" user "Package Geometry/Place Bound Top")
		(29 "B.CrtYd" user "Package Geometry/Place Bound Bottom")
		(35 "F.Fab" user "Ref Des/Assembly Top")
		(33 "B.Fab" user "Ref Des/Assembly Bottom")
	)
	(footprint ""
		(layer "F.Cu")
		(at 106.501946 -52.86248 -90)
		(property "Reference" "R6314"
			(at 0 0 270)
			(layer "F.SilkS")
			(hide yes)
			(effects
				(font
					(size 1.27 1.27)
				)
			)
		)
		(property "Value" ""
			(at 0 0 270)
			(layer "F.Fab")
			(effects
				(font
					(size 1.27 1.27)
				)
			)
		)
		(duplicate_pad_numbers_are_jumpers no)
		(fp_line
			(start -0.7874 0.4064)
			(end -0.7874 -0.4064)
			(stroke
				(width 0.1524)
				(type default)
			)
			(layer "F.SilkS")
		)
		(fp_line
			(start 0.7874 0.4064)
			(end -0.7874 0.4064)
			(stroke
				(width 0.1524)
				(type default)
			)
			(layer "F.SilkS")
		)
		(fp_line
			(start -0.7874 -0.4064)
			(end 0.7874 -0.4064)
			(stroke
				(width 0.1524)
				(type default)
			)
			(layer "F.SilkS")
		)
		(fp_line
			(start 0.7874 -0.4064)
			(end 0.7874 0.4064)
			(stroke
				(width 0.1524)
				(type default)
			)
			(layer "F.SilkS")
		)
		(fp_line
			(start -0.67945 0.3048)
			(end -0.67945 -0.305054)
			(stroke
				(width 0.1)
				(type default)
			)
			(layer "F.Fab")
		)
		(fp_line
			(start -0.12065 0.3048)
			(end -0.67945 0.3048)
			(stroke
				(width 0.1)
				(type default)
			)
			(layer "F.Fab")
		)
		(fp_line
			(start 0.120396 0.3048)
			(end 0.120396 0.2794)
			(stroke
				(width 0.1)
				(type default)
			)
			(layer "F.Fab")
		)
		(fp_line
			(start 0.67945 0.3048)
			(end 0.120396 0.3048)
			(stroke
				(width 0.1)
				(type default)
			)
			(layer "F.Fab")
		)
		(fp_line
			(start -0.12065 0.2794)
			(end -0.12065 0.3048)
			(stroke
				(width 0.1)
				(type default)
			)
			(layer "F.Fab")
		)
		(fp_line
			(start 0.120396 0.2794)
			(end -0.12065 0.2794)
			(stroke
				(width 0.1)
				(type default)
			)
			(layer "F.Fab")
		)
		(fp_line
			(start -0.12065 -0.2794)
			(end 0.12065 -0.2794)
			(stroke
				(width 0.1)
				(type default)
			)
			(layer "F.Fab")
		)
		(fp_line
			(start 0.12065 -0.2794)
			(end 0.12065 -0.3048)
			(stroke
				(width 0.1)
				(type default)
			)
			(layer "F.Fab")
		)
		(fp_line
			(start 0.12065 -0.3048)
			(end 0.67945 -0.3048)
			(stroke
				(width 0.1)
				(type default)
			)
			(layer "F.Fab")
		)
		(fp_line
			(start 0.67945 -0.3048)
			(end 0.67945 0.3048)
			(stroke
				(width 0.1)
				(type default)
			)
			(layer "F.Fab")
		)
		(fp_line
			(start -0.67945 -0.305054)
			(end -0.12065 -0.305054)
			(stroke
				(width 0.1)
				(type default)
			)
			(layer "F.Fab")
		)
		(fp_line
			(start -0.12065 -0.305054)
			(end -0.12065 -0.2794)
			(stroke
				(width 0.1)
				(type default)
			)
			(layer "F.Fab")
		)
		(pad "1" smd circle
			(at -0.40005 0 270)
			(size 0 0)
			(layers "F.Cu" "F.Mask" "F.Paste")
			(net "SMB_USB_CPU0_HUB1_SCL")
		)
		(pad "2" smd circle
			(at 0.40005 0 270)
			(size 0 0)
			(layers "F.Cu" "F.Mask" "F.Paste")
			(net "USB_HUB2_TI_OVERCUR2_MRP_PROG_FUNC5")
		)
	)
)
